# S9S_MB_2U (Grand Teton) — schematic netlist excerpt (pin names and nets, part order shuffled) for the footprints in the layout excerpt that follows; sources: Cadence DE-HDL packaged netlist, KiCad conversion of 03242023_DA0F0TMBIJ0_F0T_Motherboard_J_brd_V01_OCP.brd

R4765  Q_RES  33.2 1% CHIP  pkg 0402LF  page 216 : A = HP_LVC3_E1S_0_HSC_PWRGD ; B = HP_LVC3_E1S_0_HSC_PWRGD_PLD
R4402  Q_RES  100 1% CHIP  pkg 0402LF  page 122 : A = PVNN_TERM_CPU1 ; B = H_CPU1_MEMHOT_OUT_LVC1_R_N

(kicad_pcb
	(version 20260206)
	(generator "pcbnew")
	(generator_version "10.0")
	(general
		(thickness 1.6)
		(legacy_teardrops no)
	)
	(paper "A4")
	(title_block
		(title "03242023_DA0F0TMBIJ0_F0T_Motherboard_J_brd_V01_OCP.brd")
		(comment 1 "Grand Teton / footprints 2740-2741 of 6105")
	)
	(layers
		(0 "F.Cu" signal "TOP")
		(4 "In1.Cu" signal "GND")
		(6 "In2.Cu" signal "IN1")
		(8 "In3.Cu" signal "GND1")
		(10 "In4.Cu" signal "IN2")
		(12 "In5.Cu" signal "GND2")
		(14 "In6.Cu" signal "IN3")
		(16 "In7.Cu" signal "GND3")
		(18 "In8.Cu" signal "VCC")
		(20 "In9.Cu" signal "VCC1")
		(22 "In10.Cu" signal "GND4")
		(24 "In11.Cu" signal "IN4")
		(26 "In12.Cu" signal "GND5")
		(28 "In13.Cu" signal "IN5")
		(30 "In14.Cu" signal "GND6")
		(32 "In15.Cu" signal "IN6")
		(34 "In16.Cu" signal "GND7")
		(2 "B.Cu" signal "BOTTOM")
		(9 "F.Adhes" user "F.Adhesive")
		(11 "B.Adhes" user "B.Adhesive")
		(13 "F.Paste" user "Package Geometry/Pastemask Top")
		(15 "B.Paste" user "Package Geometry/Pastemask Bottom")
		(5 "F.SilkS" user "Ref Des/Silkscreen Top")
		(7 "B.SilkS" user "Ref Des/Silkscreen Bottom")
		(1 "F.Mask" user "Board Geometry/Soldermask Top")
		(3 "B.Mask" user "Board Geometry/Soldermask Bottom")
		(17 "Dwgs.User" user "User.Drawings")
		(19 "Cmts.User" user "User.Comments")
		(21 "Eco1.User" user "User.Eco1")
		(23 "Eco2.User" user "User.Eco2")
		(25 "Edge.Cuts" user "Board Geometry/Outline")
		(27 "Margin" user)
		(31 "F.CrtYd" user "Package Geometry/Place Bound Top")
		(29 "B.CrtYd" user "Package Geometry/Place Bound Bottom")
		(35 "F.Fab" user "Ref Des/Assembly Top")
		(33 "B.Fab" user "Ref Des/Assembly Bottom")
	)
	(footprint ""
		(layer "F.Cu")
		(at 133.02488 -92.674948 -90)
		(property "Reference" "R4402"
			(at 0 0 270)
			(layer "F.SilkS")
			(hide yes)
			(effects
				(font
					(size 1.27 1.27)
				)
			)
		)
		(property "Value" ""
			(at 0 0 270)
			(layer "F.Fab")
			(effects
				(font
					(size 1.27 1.27)
				)
			)
		)
		(duplicate_pad_numbers_are_jumpers no)
		(fp_line
			(start -0.7874 0.4064)
			(end -0.7874 -0.4064)
			(stroke
				(width 0.1524)
				(type default)
			)
			(layer "F.SilkS")
		)
		(fp_line
			(start 0.7874 0.4064)
			(end -0.7874 0.4064)
			(stroke
				(width 0.1524)
				(type default)
			)
			(layer "F.SilkS")
		)
		(fp_line
			(start -0.7874 -0.4064)
			(end 0.7874 -0.4064)
			(stroke
				(width 0.1524)
				(type default)
			)
			(layer "F.SilkS")
		)
		(fp_line
			(start 0.7874 -0.4064)
			(end 0.7874 0.4064)
			(stroke
				(width 0.1524)
				(type default)
			)
			(layer "F.SilkS")
		)
		(fp_line
			(start -0.67945 0.3048)
			(end -0.67945 -0.305054)
			(stroke
				(width 0.1)
				(type default)
			)
			(layer "F.Fab")
		)
		(fp_line
			(start -0.12065 0.3048)
			(end -0.67945 0.3048)
			(stroke
				(width 0.1)
				(type default)
			)
			(layer "F.Fab")
		)
		(fp_line
			(start 0.120396 0.3048)
			(end 0.120396 0.2794)
			(stroke
				(width 0.1)
				(type default)
			)
			(layer "F.Fab")
		)
		(fp_line
			(start 0.67945 0.3048)
			(end 0.120396 0.3048)
			(stroke
				(width 0.1)
				(type default)
			)
			(layer "F.Fab")
		)
		(fp_line
			(start -0.12065 0.2794)
			(end -0.12065 0.3048)
			(stroke
				(width 0.1)
				(type default)
			)
			(layer "F.Fab")
		)
		(fp_line
			(start 0.120396 0.2794)
			(end -0.12065 0.2794)
			(stroke
				(width 0.1)
				(type default)
			)
			(layer "F.Fab")
		)
		(fp_line
			(start -0.12065 -0.2794)
			(end 0.12065 -0.2794)
			(stroke
				(width 0.1)
				(type default)
			)
			(layer "F.Fab")
		)
		(fp_line
			(start 0.12065 -0.2794)
			(end 0.12065 -0.3048)
			(stroke
				(width 0.1)
				(type default)
			)
			(layer "F.Fab")
		)
		(fp_line
			(start 0.12065 -0.3048)
			(end 0.67945 -0.3048)
			(stroke
				(width 0.1)
				(type default)
			)
			(layer "F.Fab")
		)
		(fp_line
			(start 0.67945 -0.3048)
			(end 0.67945 0.3048)
			(stroke
				(width 0.1)
				(type default)
			)
			(layer "F.Fab")
		)
		(fp_line
			(start -0.67945 -0.305054)
			(end -0.12065 -0.305054)
			(stroke
				(width 0.1)
				(type default)
			)
			(layer "F.Fab")
		)
		(fp_line
			(start -0.12065 -0.305054)
			(end -0.12065 -0.2794)
			(stroke
				(width 0.1)
				(type default)
			)
			(layer "F.Fab")
		)
		(pad "1" smd circle
			(at -0.40005 0 270)
			(size 0 0)
			(layers "F.Cu" "F.Mask" "F.Paste")
			(net "PVNN_TERM_CPU1")
		)
		(pad "2" smd circle
			(at 0.40005 0 270)
			(size 0 0)
			(layers "F.Cu" "F.Mask" "F.Paste")
			(net "H_CPU1_MEMHOT_OUT_LVC1_R_N")
		)
	)
	(footprint ""
		(layer "F.Cu")
		(at 183.515 -93.91015 90)
		(property "Reference" "R4765"
			(at 0 0 90)
			(layer "F.SilkS")
			(hide yes)
			(effects
				(font
					(size 1.27 1.27)
				)
			)
		)
		(property "Value" ""
			(at 0 0 90)
			(layer "F.Fab")
			(effects
				(font
					(size 1.27 1.27)
				)
			)
		)
		(duplicate_pad_numbers_are_jumpers no)
		(fp_line
			(start 0.7874 -0.4064)
			(end 0.7874 0.4064)
			(stroke
				(width 0.1524)
				(type default)
			)
			(layer "F.SilkS")
		)
		(fp_line
			(start -0.7874 -0.4064)
			(end 0.7874 -0.4064)
			(stroke
				(width 0.1524)
				(type default)
			)
			(layer "F.SilkS")
		)
		(fp_line
			(start 0.7874 0.4064)
			(end -0.7874 0.4064)
			(stroke
				(width 0.1524)
				(type default)
			)
			(layer "F.SilkS")
		)
		(fp_line
			(start -0.7874 0.4064)
			(end -0.7874 -0.4064)
			(stroke
				(width 0.1524)
				(type default)
			)
			(layer "F.SilkS")
		)
		(fp_line
			(start -0.12065 -0.305054)
			(end -0.12065 -0.2794)
			(stroke
				(width 0.1)
				(type default)
			)
			(layer "F.Fab")
		)
		(fp_line
			(start -0.67945 -0.305054)
			(end -0.12065 -0.305054)
			(stroke
				(width 0.1)
				(type default)
			)
			(layer "F.Fab")
		)
		(fp_line
			(start 0.67945 -0.3048)
			(end 0.67945 0.3048)
			(stroke
				(width 0.1)
				(type default)
			)
			(layer "F.Fab")
		)
		(fp_line
			(start 0.12065 -0.3048)
			(end 0.67945 -0.3048)
			(stroke
				(width 0.1)
				(type default)
			)
			(layer "F.Fab")
		)
		(fp_line
			(start 0.12065 -0.2794)
			(end 0.12065 -0.3048)
			(stroke
				(width 0.1)
				(type default)
			)
			(layer "F.Fab")
		)
		(fp_line
			(start -0.12065 -0.2794)
			(end 0.12065 -0.2794)
			(stroke
				(width 0.1)
				(type default)
			)
			(layer "F.Fab")
		)
		(fp_line
			(start 0.120396 0.2794)
			(end -0.12065 0.2794)
			(stroke
				(width 0.1)
				(type default)
			)
			(layer "F.Fab")
		)
		(fp_line
			(start -0.12065 0.2794)
			(end -0.12065 0.3048)
			(stroke
				(width 0.1)
				(type default)
			)
			(layer "F.Fab")
		)
		(fp_line
			(start 0.67945 0.3048)
			(end 0.120396 0.3048)
			(stroke
				(width 0.1)
				(type default)
			)
			(layer "F.Fab")
		)
		(fp_line
			(start 0.120396 0.3048)
			(end 0.120396 0.2794)
			(stroke
				(width 0.1)
				(type default)
			)
			(layer "F.Fab")
		)
		(fp_line
			(start -0.12065 0.3048)
			(end -0.67945 0.3048)
			(stroke
				(width 0.1)
				(type default)
			)
			(layer "F.Fab")
		)
		(fp_line
			(start -0.67945 0.3048)
			(end -0.67945 -0.305054)
			(stroke
				(width 0.1)
				(type default)
			)
			(layer "F.Fab")
		)
		(pad "1" smd circle
			(at -0.40005 0 90)
			(size 0 0)
			(layers "F.Cu" "F.Mask" "F.Paste")
			(net "HP_LVC3_E1S_0_HSC_PWRGD")
		)
		(pad "2" smd circle
			(at 0.40005 0 90)
			(size 0 0)
			(layers "F.Cu" "F.Mask" "F.Paste")
			(net "HP_LVC3_E1S_0_HSC_PWRGD_PLD")
		)
	)
)
